# T6G (Grand Teton) — schematic netlist excerpt (pin names and nets, part order shuffled) for the footprints in the layout excerpt that follows; sources: Cadence DE-HDL packaged netlist, KiCad conversion of 04192023_DAF0TMB3IC0_F0TG_MB_C_brd_V02_OCP.brd

PR3990  Q_RES  2K 0.1% CHIP  pkg 0402LF  page 264 : A = HSC_IMON ; B = AGND_HSC
C856  Q_CAP_DIFFBUS  DIFF BUS_0.22UF 6.3V 20% X6S  pkg C0201  page 64 : \1\ = P5E_CPU0_P2_TX_C_DN<6> ; \2\ = P5E_CPU0_P2_TX_DN<6>
R2836  Q_RES  4.7K 5% CHIP  pkg 0402LF  page 127 : A = P3V3_AUX ; B = FM_SWB_BIC_READY

(kicad_pcb
	(version 20260206)
	(generator "pcbnew")
	(generator_version "10.0")
	(general
		(thickness 1.6)
		(legacy_teardrops no)
	)
	(paper "A4")
	(title_block
		(title "04192023_DAF0TMB3IC0_F0TG_MB_C_brd_V02_OCP.brd")
		(comment 1 "Grand Teton / footprints 3712-3714 of 8354")
	)
	(layers
		(0 "F.Cu" signal "TOP")
		(4 "In1.Cu" signal "GND")
		(6 "In2.Cu" signal "IN1")
		(8 "In3.Cu" signal "GND1")
		(10 "In4.Cu" signal "IN2")
		(12 "In5.Cu" signal "GND2")
		(14 "In6.Cu" signal "IN3")
		(16 "In7.Cu" signal "GND3")
		(18 "In8.Cu" signal "VCC")
		(20 "In9.Cu" signal "VCC1")
		(22 "In10.Cu" signal "GND4")
		(24 "In11.Cu" signal "IN4")
		(26 "In12.Cu" signal "GND5")
		(28 "In13.Cu" signal "IN5")
		(30 "In14.Cu" signal "GND6")
		(32 "In15.Cu" signal "IN6")
		(34 "In16.Cu" signal "GND7")
		(2 "B.Cu" signal "BOTTOM")
		(9 "F.Adhes" user "F.Adhesive")
		(11 "B.Adhes" user "B.Adhesive")
		(13 "F.Paste" user "Package Geometry/Pastemask Top")
		(15 "B.Paste" user "Package Geometry/Pastemask Bottom")
		(5 "F.SilkS" user "Ref Des/Silkscreen Top")
		(7 "B.SilkS" user "Ref Des/Silkscreen Bottom")
		(1 "F.Mask" user "Board Geometry/Soldermask Top")
		(3 "B.Mask" user "Board Geometry/Soldermask Bottom")
		(17 "Dwgs.User" user "User.Drawings")
		(19 "Cmts.User" user "User.Comments")
		(21 "Eco1.User" user "User.Eco1")
		(23 "Eco2.User" user "User.Eco2")
		(25 "Edge.Cuts" user "Board Geometry/Outline")
		(27 "Margin" user)
		(31 "F.CrtYd" user "Package Geometry/Place Bound Top")
		(29 "B.CrtYd" user "Package Geometry/Place Bound Bottom")
		(35 "F.Fab" user "Ref Des/Assembly Top")
		(33 "B.Fab" user "Ref Des/Assembly Bottom")
	)
	(footprint ""
		(layer "F.Cu")
		(at 434.43144 -434.467508 90)
		(property "Reference" "R2836"
			(at 0 0 90)
			(layer "F.SilkS")
			(hide yes)
			(effects
				(font
					(size 1.27 1.27)
				)
			)
		)
		(property "Value" ""
			(at 0 0 90)
			(layer "F.Fab")
			(effects
				(font
					(size 1.27 1.27)
				)
			)
		)
		(duplicate_pad_numbers_are_jumpers no)
		(fp_line
			(start 0.7874 -0.4064)
			(end 0.7874 0.4064)
			(stroke
				(width 0.1524)
				(type default)
			)
			(layer "F.SilkS")
		)
		(fp_line
			(start -0.7874 -0.4064)
			(end 0.7874 -0.4064)
			(stroke
				(width 0.1524)
				(type default)
			)
			(layer "F.SilkS")
		)
		(fp_line
			(start 0.7874 0.4064)
			(end -0.7874 0.4064)
			(stroke
				(width 0.1524)
				(type default)
			)
			(layer "F.SilkS")
		)
		(fp_line
			(start -0.7874 0.4064)
			(end -0.7874 -0.4064)
			(stroke
				(width 0.1524)
				(type default)
			)
			(layer "F.SilkS")
		)
		(fp_line
			(start -0.12065 -0.305054)
			(end -0.12065 -0.2794)
			(stroke
				(width 0.1)
				(type default)
			)
			(layer "F.Fab")
		)
		(fp_line
			(start -0.67945 -0.305054)
			(end -0.12065 -0.305054)
			(stroke
				(width 0.1)
				(type default)
			)
			(layer "F.Fab")
		)
		(fp_line
			(start 0.67945 -0.3048)
			(end 0.67945 0.3048)
			(stroke
				(width 0.1)
				(type default)
			)
			(layer "F.Fab")
		)
		(fp_line
			(start 0.12065 -0.3048)
			(end 0.67945 -0.3048)
			(stroke
				(width 0.1)
				(type default)
			)
			(layer "F.Fab")
		)
		(fp_line
			(start 0.12065 -0.2794)
			(end 0.12065 -0.3048)
			(stroke
				(width 0.1)
				(type default)
			)
			(layer "F.Fab")
		)
		(fp_line
			(start -0.12065 -0.2794)
			(end 0.12065 -0.2794)
			(stroke
				(width 0.1)
				(type default)
			)
			(layer "F.Fab")
		)
		(fp_line
			(start 0.120396 0.2794)
			(end -0.12065 0.2794)
			(stroke
				(width 0.1)
				(type default)
			)
			(layer "F.Fab")
		)
		(fp_line
			(start -0.12065 0.2794)
			(end -0.12065 0.3048)
			(stroke
				(width 0.1)
				(type default)
			)
			(layer "F.Fab")
		)
		(fp_line
			(start 0.67945 0.3048)
			(end 0.120396 0.3048)
			(stroke
				(width 0.1)
				(type default)
			)
			(layer "F.Fab")
		)
		(fp_line
			(start 0.120396 0.3048)
			(end 0.120396 0.2794)
			(stroke
				(width 0.1)
				(type default)
			)
			(layer "F.Fab")
		)
		(fp_line
			(start -0.12065 0.3048)
			(end -0.67945 0.3048)
			(stroke
				(width 0.1)
				(type default)
			)
			(layer "F.Fab")
		)
		(fp_line
			(start -0.67945 0.3048)
			(end -0.67945 -0.305054)
			(stroke
				(width 0.1)
				(type default)
			)
			(layer "F.Fab")
		)
		(pad "1" smd circle
			(at -0.40005 0 90)
			(size 0 0)
			(layers "F.Cu" "F.Mask" "F.Paste")
			(net "P3V3_AUX")
		)
		(pad "2" smd circle
			(at 0.40005 0 90)
			(size 0 0)
			(layers "F.Cu" "F.Mask" "F.Paste")
			(net "FM_SWB_BIC_READY")
		)
	)
	(footprint ""
		(layer "F.Cu")
		(at 408.04084 -378.95403 -90)
		(property "Reference" "C856"
			(at 0 0 270)
			(layer "F.SilkS")
			(hide yes)
			(effects
				(font
					(size 1.27 1.27)
				)
			)
		)
		(property "Value" ""
			(at 0 0 270)
			(layer "F.Fab")
			(effects
				(font
					(size 1.27 1.27)
				)
			)
		)
		(duplicate_pad_numbers_are_jumpers no)
		(fp_line
			(start -0.299974 0.150114)
			(end -0.299974 -0.150114)
			(stroke
				(width 0.1)
				(type default)
			)
			(layer "F.Fab")
		)
		(fp_line
			(start 0.299974 0.150114)
			(end -0.299974 0.150114)
			(stroke
				(width 0.1)
				(type default)
			)
			(layer "F.Fab")
		)
		(fp_line
			(start -0.299974 -0.150114)
			(end 0.299974 -0.150114)
			(stroke
				(width 0.1)
				(type default)
			)
			(layer "F.Fab")
		)
		(fp_line
			(start 0.299974 -0.150114)
			(end 0.299974 0.150114)
			(stroke
				(width 0.1)
				(type default)
			)
			(layer "F.Fab")
		)
		(pad "1" smd rect
			(at -0.2667 0 270)
			(size 0.3048 0.381)
			(layers "F.Cu" "F.Mask" "F.Paste")
			(net "P5E_CPU0_P2_TX_C_DN<6>")
		)
		(pad "2" smd rect
			(at 0.2667 0 270)
			(size 0.3048 0.381)
			(layers "F.Cu" "F.Mask" "F.Paste")
			(net "P5E_CPU0_P2_TX_DN<6>")
		)
	)
	(footprint ""
		(layer "F.Cu")
		(at 215.4301 -401.988782 180)
		(property "Reference" "PR3990"
			(at 0 0 180)
			(layer "F.SilkS")
			(hide yes)
			(effects
				(font
					(size 1.27 1.27)
				)
			)
		)
		(property "Value" ""
			(at 0 0 180)
			(layer "F.Fab")
			(effects
				(font
					(size 1.27 1.27)
				)
			)
		)
		(duplicate_pad_numbers_are_jumpers no)
		(fp_line
			(start 0.7874 0.4064)
			(end -0.7874 0.4064)
			(stroke
				(width 0.1524)
				(type default)
			)
			(layer "F.SilkS")
		)
		(fp_line
			(start 0.7874 -0.4064)
			(end 0.7874 0.4064)
			(stroke
				(width 0.1524)
				(type default)
			)
			(layer "F.SilkS")
		)
		(fp_line
			(start -0.7874 0.4064)
			(end -0.7874 -0.4064)
			(stroke
				(width 0.1524)
				(type default)
			)
			(layer "F.SilkS")
		)
		(fp_line
			(start -0.7874 -0.4064)
			(end 0.7874 -0.4064)
			(stroke
				(width 0.1524)
				(type default)
			)
			(layer "F.SilkS")
		)
		(fp_line
			(start 0.67945 0.3048)
			(end 0.120396 0.3048)
			(stroke
				(width 0.1)
				(type default)
			)
			(layer "F.Fab")
		)
		(fp_line
			(start 0.67945 -0.3048)
			(end 0.67945 0.3048)
			(stroke
				(width 0.1)
				(type default)
			)
			(layer "F.Fab")
		)
		(fp_line
			(start 0.12065 -0.2794)
			(end 0.12065 -0.3048)
			(stroke
				(width 0.1)
				(type default)
			)
			(layer "F.Fab")
		)
		(fp_line
			(start 0.12065 -0.3048)
			(end 0.67945 -0.3048)
			(stroke
				(width 0.1)
				(type default)
			)
			(layer "F.Fab")
		)
		(fp_line
			(start 0.120396 0.3048)
			(end 0.120396 0.2794)
			(stroke
				(width 0.1)
				(type default)
			)
			(layer "F.Fab")
		)
		(fp_line
			(start 0.120396 0.2794)
			(end -0.12065 0.2794)
			(stroke
				(width 0.1)
				(type default)
			)
			(layer "F.Fab")
		)
		(fp_line
			(start -0.12065 0.3048)
			(end -0.67945 0.3048)
			(stroke
				(width 0.1)
				(type default)
			)
			(layer "F.Fab")
		)
		(fp_line
			(start -0.12065 0.2794)
			(end -0.12065 0.3048)
			(stroke
				(width 0.1)
				(type default)
			)
			(layer "F.Fab")
		)
		(fp_line
			(start -0.12065 -0.2794)
			(end 0.12065 -0.2794)
			(stroke
				(width 0.1)
				(type default)
			)
			(layer "F.Fab")
		)
		(fp_line
			(start -0.12065 -0.305054)
			(end -0.12065 -0.2794)
			(stroke
				(width 0.1)
				(type default)
			)
			(layer "F.Fab")
		)
		(fp_line
			(start -0.67945 0.3048)
			(end -0.67945 -0.305054)
			(stroke
				(width 0.1)
				(type default)
			)
			(layer "F.Fab")
		)
		(fp_line
			(start -0.67945 -0.305054)
			(end -0.12065 -0.305054)
			(stroke
				(width 0.1)
				(type default)
			)
			(layer "F.Fab")
		)
		(pad "1" smd circle
			(at -0.40005 0 180)
			(size 0 0)
			(layers "F.Cu" "F.Mask" "F.Paste")
			(net "HSC_IMON")
		)
		(pad "2" smd circle
			(at 0.40005 0 180)
			(size 0 0)
			(layers "F.Cu" "F.Mask" "F.Paste")
			(net "AGND_HSC")
		)
	)
)
